(kicad_pcb
	(version 20241229)
	(generator "pcbnew")
	(generator_version "9.0")
	(general
		(thickness 1.6)
		(legacy_teardrops no)
	)
	(paper "A4")
	(title_block
		(title "LPDDR4 testbed")
		(date "2024-03-26")
		(rev "1.2.2")
		(comment 9 "footprints 66-66 of 66")
	)
	(layers
		(0 "F.Cu" signal)
		(4 "In1.Cu" power)
		(6 "In2.Cu" power)
		(8 "In3.Cu" signal)
		(10 "In4.Cu" signal)
		(2 "B.Cu" signal)
		(9 "F.Adhes" user "F.Adhesive")
		(11 "B.Adhes" user "B.Adhesive")
		(13 "F.Paste" user)
		(15 "B.Paste" user)
		(5 "F.SilkS" user "F.Silkscreen")
		(7 "B.SilkS" user "B.Silkscreen")
		(1 "F.Mask" user)
		(3 "B.Mask" user)
		(17 "Dwgs.User" user "User.Drawings")
		(19 "Cmts.User" user "User.Comments")
		(21 "Eco1.User" user "User.Eco1")
		(23 "Eco2.User" user "User.Eco2")
		(25 "Edge.Cuts" user)
		(27 "Margin" user)
		(31 "F.CrtYd" user "F.Courtyard")
		(29 "B.CrtYd" user "B.Courtyard")
		(35 "F.Fab" user)
		(33 "B.Fab" user)
	)
	(footprint "antmicro-footprints:C_0201"
		(layer "B.Cu")
		(at 146.575 86.1 180)
		(descr "Capacitor SMD 0201")
		(tags "capacitor SMD 0201")
		(property "Reference" "C36"
			(at -1.1 -1.25 0)
			(layer "B.SilkS")
			(effects
				(font
					(size 0.7 0.7)
					(thickness 0.15)
				)
				(justify left bottom mirror)
			)
		)
		(property "Value" "C_100n_0201"
			(at 0 -1.4 0)
			(layer "B.Fab")
			(effects
				(font
					(size 0.7 0.7)
					(thickness 0.15)
				)
				(justify left bottom mirror)
			)
		)
		(property "Description" " "
			(at 0 0 180)
			(layer "F.Fab")
			(hide yes)
			(effects
				(font
					(size 1.27 1.27)
					(thickness 0.15)
				)
			)
		)
		(property "Author" "Antmicro"
			(at 293.15 172.2 0)
			(layer "B.Fab")
			(hide yes)
			(effects
				(font
					(size 1 1)
					(thickness 0.15)
				)
				(justify mirror)
			)
		)
		(property "Dielectric" ""
			(at 293.15 172.2 0)
			(layer "B.Fab")
			(hide yes)
			(effects
				(font
					(size 1 1)
					(thickness 0.15)
				)
				(justify mirror)
			)
		)
		(property "License" "Apache-2.0"
			(at 293.15 172.2 0)
			(layer "B.Fab")
			(hide yes)
			(effects
				(font
					(size 1 1)
					(thickness 0.15)
				)
				(justify mirror)
			)
		)
		(property "MPN" "CC0201KRX6S5BB104"
			(at 293.15 172.2 0)
			(layer "B.Fab")
			(hide yes)
			(effects
				(font
					(size 1 1)
					(thickness 0.15)
				)
				(justify mirror)
			)
		)
		(property "Manufacturer" "YAGEO"
			(at 293.15 172.2 0)
			(layer "B.Fab")
			(hide yes)
			(effects
				(font
					(size 1 1)
					(thickness 0.15)
				)
				(justify mirror)
			)
		)
		(property "Val" "100n"
			(at 293.15 172.2 0)
			(layer "B.Fab")
			(hide yes)
			(effects
				(font
					(size 1 1)
					(thickness 0.15)
				)
				(justify mirror)
			)
		)
		(property "Voltage" ""
			(at 293.15 172.2 0)
			(layer "B.Fab")
			(hide yes)
			(effects
				(font
					(size 1 1)
					(thickness 0.15)
				)
				(justify mirror)
			)
		)
		(sheetname "LPDDR4")
		(sheetfile "lpddr4.kicad_sch")
		(attr smd)
		(fp_rect
			(start -0.72 0.38)
			(end 0.72 -0.38)
			(stroke
				(width 0.05)
				(type solid)
			)
			(fill no)
			(layer "B.CrtYd")
		)
		(fp_rect
			(start 0.3 -0.15)
			(end -0.301 0.149)
			(stroke
				(width 0.15)
				(type solid)
			)
			(fill no)
			(layer "B.Fab")
		)
		(pad "" smd roundrect
			(at -0.349 0.002 180)
			(size 0.318 0.36)
			(layers "B.Paste")
			(roundrect_rratio 0.25)
		)
		(pad "" smd roundrect
			(at 0.341 0.002 180)
			(size 0.318 0.36)
			(layers "B.Paste")
			(roundrect_rratio 0.25)
		)
		(pad "1" smd roundrect
			(at -0.321 0.002 180)
			(size 0.46 0.4)
			(layers "B.Cu" "B.Mask")
			(roundrect_rratio 0.25)
			(net 36 "GND")
			(pintype "passive")
		)
		(pad "2" smd roundrect
			(at 0.32 0.002 180)
			(size 0.46 0.4)
			(layers "B.Cu" "B.Mask")
			(roundrect_rratio 0.25)
			(net 188 "VDD2")
			(pintype "passive")
		)
	)
)
